# S9S_MB_2U (Grand Teton) — schematic netlist excerpt (pin names and nets, part order shuffled) for the footprints in the layout excerpt that follows; sources: Cadence DE-HDL packaged netlist, KiCad conversion of 03242023_DA0F0TMBIJ0_F0T_Motherboard_J_brd_V01_OCP.brd

C2341  Q_CAP  0.1UF 25V 10% X7R  pkg 0402  page 145 : A = P3V3_AUX ; B = GND
PR519  Q_RES  100 1% CHIP  pkg 0402LF  page 274 : A = VSENSE_PVCCINFAON_CPU0_DN ; B = GND

(kicad_pcb
	(version 20260206)
	(generator "pcbnew")
	(generator_version "10.0")
	(general
		(thickness 1.6)
		(legacy_teardrops no)
	)
	(paper "A4")
	(title_block
		(title "03242023_DA0F0TMBIJ0_F0T_Motherboard_J_brd_V01_OCP.brd")
		(comment 1 "Grand Teton / footprints 2944-2945 of 6105")
	)
	(layers
		(0 "F.Cu" signal "TOP")
		(4 "In1.Cu" signal "GND")
		(6 "In2.Cu" signal "IN1")
		(8 "In3.Cu" signal "GND1")
		(10 "In4.Cu" signal "IN2")
		(12 "In5.Cu" signal "GND2")
		(14 "In6.Cu" signal "IN3")
		(16 "In7.Cu" signal "GND3")
		(18 "In8.Cu" signal "VCC")
		(20 "In9.Cu" signal "VCC1")
		(22 "In10.Cu" signal "GND4")
		(24 "In11.Cu" signal "IN4")
		(26 "In12.Cu" signal "GND5")
		(28 "In13.Cu" signal "IN5")
		(30 "In14.Cu" signal "GND6")
		(32 "In15.Cu" signal "IN6")
		(34 "In16.Cu" signal "GND7")
		(2 "B.Cu" signal "BOTTOM")
		(9 "F.Adhes" user "F.Adhesive")
		(11 "B.Adhes" user "B.Adhesive")
		(13 "F.Paste" user "Package Geometry/Pastemask Top")
		(15 "B.Paste" user "Package Geometry/Pastemask Bottom")
		(5 "F.SilkS" user "Ref Des/Silkscreen Top")
		(7 "B.SilkS" user "Ref Des/Silkscreen Bottom")
		(1 "F.Mask" user "Board Geometry/Soldermask Top")
		(3 "B.Mask" user "Board Geometry/Soldermask Bottom")
		(17 "Dwgs.User" user "User.Drawings")
		(19 "Cmts.User" user "User.Comments")
		(21 "Eco1.User" user "User.Eco1")
		(23 "Eco2.User" user "User.Eco2")
		(25 "Edge.Cuts" user "Board Geometry/Outline")
		(27 "Margin" user)
		(31 "F.CrtYd" user "Package Geometry/Place Bound Top")
		(29 "B.CrtYd" user "Package Geometry/Place Bound Bottom")
		(35 "F.Fab" user "Ref Des/Assembly Top")
		(33 "B.Fab" user "Ref Des/Assembly Bottom")
	)
	(footprint ""
		(layer "F.Cu")
		(at 361.25658 -407.228548)
		(property "Reference" "C2341"
			(at 0 0 0)
			(layer "F.SilkS")
			(hide yes)
			(effects
				(font
					(size 1.27 1.27)
				)
			)
		)
		(property "Value" ""
			(at 0 0 0)
			(layer "F.Fab")
			(effects
				(font
					(size 1.27 1.27)
				)
			)
		)
		(duplicate_pad_numbers_are_jumpers no)
		(fp_line
			(start -0.7874 -0.4064)
			(end 0.7874 -0.4064)
			(stroke
				(width 0.1524)
				(type default)
			)
			(layer "F.SilkS")
		)
		(fp_line
			(start -0.7874 0.4064)
			(end -0.7874 -0.4064)
			(stroke
				(width 0.1524)
				(type default)
			)
			(layer "F.SilkS")
		)
		(fp_line
			(start 0.7874 -0.4064)
			(end 0.7874 0.4064)
			(stroke
				(width 0.1524)
				(type default)
			)
			(layer "F.SilkS")
		)
		(fp_line
			(start 0.7874 0.4064)
			(end -0.7874 0.4064)
			(stroke
				(width 0.1524)
				(type default)
			)
			(layer "F.SilkS")
		)
		(fp_line
			(start -0.67945 -0.305054)
			(end -0.12065 -0.305054)
			(stroke
				(width 0.1)
				(type default)
			)
			(layer "F.Fab")
		)
		(fp_line
			(start -0.67945 0.3048)
			(end -0.67945 -0.305054)
			(stroke
				(width 0.1)
				(type default)
			)
			(layer "F.Fab")
		)
		(fp_line
			(start -0.12065 -0.305054)
			(end -0.12065 -0.2794)
			(stroke
				(width 0.1)
				(type default)
			)
			(layer "F.Fab")
		)
		(fp_line
			(start -0.12065 -0.2794)
			(end 0.12065 -0.2794)
			(stroke
				(width 0.1)
				(type default)
			)
			(layer "F.Fab")
		)
		(fp_line
			(start -0.12065 0.2794)
			(end -0.12065 0.3048)
			(stroke
				(width 0.1)
				(type default)
			)
			(layer "F.Fab")
		)
		(fp_line
			(start -0.12065 0.3048)
			(end -0.67945 0.3048)
			(stroke
				(width 0.1)
				(type default)
			)
			(layer "F.Fab")
		)
		(fp_line
			(start 0.120396 0.2794)
			(end -0.12065 0.2794)
			(stroke
				(width 0.1)
				(type default)
			)
			(layer "F.Fab")
		)
		(fp_line
			(start 0.120396 0.3048)
			(end 0.120396 0.2794)
			(stroke
				(width 0.1)
				(type default)
			)
			(layer "F.Fab")
		)
		(fp_line
			(start 0.12065 -0.3048)
			(end 0.67945 -0.3048)
			(stroke
				(width 0.1)
				(type default)
			)
			(layer "F.Fab")
		)
		(fp_line
			(start 0.12065 -0.2794)
			(end 0.12065 -0.3048)
			(stroke
				(width 0.1)
				(type default)
			)
			(layer "F.Fab")
		)
		(fp_line
			(start 0.67945 -0.3048)
			(end 0.67945 0.3048)
			(stroke
				(width 0.1)
				(type default)
			)
			(layer "F.Fab")
		)
		(fp_line
			(start 0.67945 0.3048)
			(end 0.120396 0.3048)
			(stroke
				(width 0.1)
				(type default)
			)
			(layer "F.Fab")
		)
		(pad "1" smd circle
			(at -0.40005 0)
			(size 0 0)
			(layers "F.Cu" "F.Mask" "F.Paste")
			(net "P3V3_AUX")
		)
		(pad "2" smd circle
			(at 0.40005 0)
			(size 0 0)
			(layers "F.Cu" "F.Mask" "F.Paste")
			(net "GND")
		)
	)
	(footprint ""
		(layer "F.Cu")
		(at 398.133824 -185.96991)
		(property "Reference" "PR519"
			(at 0 0 0)
			(layer "F.SilkS")
			(hide yes)
			(effects
				(font
					(size 1.27 1.27)
				)
			)
		)
		(property "Value" ""
			(at 0 0 0)
			(layer "F.Fab")
			(effects
				(font
					(size 1.27 1.27)
				)
			)
		)
		(duplicate_pad_numbers_are_jumpers no)
		(fp_line
			(start -0.7874 -0.4064)
			(end 0.7874 -0.4064)
			(stroke
				(width 0.1524)
				(type default)
			)
			(layer "F.SilkS")
		)
		(fp_line
			(start -0.7874 0.4064)
			(end -0.7874 -0.4064)
			(stroke
				(width 0.1524)
				(type default)
			)
			(layer "F.SilkS")
		)
		(fp_line
			(start 0.7874 -0.4064)
			(end 0.7874 0.4064)
			(stroke
				(width 0.1524)
				(type default)
			)
			(layer "F.SilkS")
		)
		(fp_line
			(start 0.7874 0.4064)
			(end -0.7874 0.4064)
			(stroke
				(width 0.1524)
				(type default)
			)
			(layer "F.SilkS")
		)
		(fp_line
			(start -0.67945 -0.305054)
			(end -0.12065 -0.305054)
			(stroke
				(width 0.1)
				(type default)
			)
			(layer "F.Fab")
		)
		(fp_line
			(start -0.67945 0.3048)
			(end -0.67945 -0.305054)
			(stroke
				(width 0.1)
				(type default)
			)
			(layer "F.Fab")
		)
		(fp_line
			(start -0.12065 -0.305054)
			(end -0.12065 -0.2794)
			(stroke
				(width 0.1)
				(type default)
			)
			(layer "F.Fab")
		)
		(fp_line
			(start -0.12065 -0.2794)
			(end 0.12065 -0.2794)
			(stroke
				(width 0.1)
				(type default)
			)
			(layer "F.Fab")
		)
		(fp_line
			(start -0.12065 0.2794)
			(end -0.12065 0.3048)
			(stroke
				(width 0.1)
				(type default)
			)
			(layer "F.Fab")
		)
		(fp_line
			(start -0.12065 0.3048)
			(end -0.67945 0.3048)
			(stroke
				(width 0.1)
				(type default)
			)
			(layer "F.Fab")
		)
		(fp_line
			(start 0.120396 0.2794)
			(end -0.12065 0.2794)
			(stroke
				(width 0.1)
				(type default)
			)
			(layer "F.Fab")
		)
		(fp_line
			(start 0.120396 0.3048)
			(end 0.120396 0.2794)
			(stroke
				(width 0.1)
				(type default)
			)
			(layer "F.Fab")
		)
		(fp_line
			(start 0.12065 -0.3048)
			(end 0.67945 -0.3048)
			(stroke
				(width 0.1)
				(type default)
			)
			(layer "F.Fab")
		)
		(fp_line
			(start 0.12065 -0.2794)
			(end 0.12065 -0.3048)
			(stroke
				(width 0.1)
				(type default)
			)
			(layer "F.Fab")
		)
		(fp_line
			(start 0.67945 -0.3048)
			(end 0.67945 0.3048)
			(stroke
				(width 0.1)
				(type default)
			)
			(layer "F.Fab")
		)
		(fp_line
			(start 0.67945 0.3048)
			(end 0.120396 0.3048)
			(stroke
				(width 0.1)
				(type default)
			)
			(layer "F.Fab")
		)
		(pad "1" smd circle
			(at -0.40005 0)
			(size 0 0)
			(layers "F.Cu" "F.Mask" "F.Paste")
			(net "VSENSE_PVCCINFAON_CPU0_DN")
		)
		(pad "2" smd circle
			(at 0.40005 0)
			(size 0 0)
			(layers "F.Cu" "F.Mask" "F.Paste")
			(net "GND")
		)
	)
)
